# SCM (Grand Teton) — schematic netlist excerpt (pin names and nets, part order shuffled) for the footprints in the layout excerpt that follows; sources: Cadence DE-HDL packaged netlist, KiCad conversion of 12092022_DA0F0TMDCD0_F0T_Management_Board_D_brd_V3_OCP.brd

C200  Q_CAP  0.1UF 25V 10% X7R  pkg 0402  page 50 : A = P3V3_AUX ; B = GND

U34  DT1240E04LP7  DT1240E-04LP-7 IC  pkg U-DFN2510-10_0-5_2-5X1  page 23
  IO1  = V_BMC_LS_DDC_SCL_R
  IO2  = V_BMC_LS_DDC_SDA_R
  VSS1  = GND
  IO3  = V_VGAHS_BUF
  IO4  = V_VGAVS_BUF
  NC1  = V_VGAVS_BUF
  NC2  = V_VGAHS_BUF
  VSS2  = GND
  NC3  = V_BMC_LS_DDC_SDA_R
  NC4  = V_BMC_LS_DDC_SCL_R

(kicad_pcb
	(version 20260206)
	(generator "pcbnew")
	(generator_version "10.0")
	(general
		(thickness 1.6)
		(legacy_teardrops no)
	)
	(paper "A4")
	(title_block
		(title "12092022_DA0F0TMDCD0_F0T_Management_Board_D_brd_V3_OCP.brd")
		(comment 1 "Grand Teton / footprints 204-205 of 1440")
	)
	(layers
		(0 "F.Cu" signal "TOP")
		(4 "In1.Cu" signal "GND")
		(6 "In2.Cu" signal "IN1")
		(8 "In3.Cu" signal "GND1")
		(10 "In4.Cu" signal "IN2")
		(12 "In5.Cu" signal "VCC")
		(14 "In6.Cu" signal "VCC1")
		(16 "In7.Cu" signal "IN3")
		(18 "In8.Cu" signal "GND2")
		(20 "In9.Cu" signal "IN4")
		(22 "In10.Cu" signal "GND3")
		(2 "B.Cu" signal "BOTTOM")
		(9 "F.Adhes" user "F.Adhesive")
		(11 "B.Adhes" user "B.Adhesive")
		(13 "F.Paste" user "Package Geometry/Pastemask Top")
		(15 "B.Paste" user "Package Geometry/Pastemask Bottom")
		(5 "F.SilkS" user "Ref Des/Silkscreen Top")
		(7 "B.SilkS" user "Ref Des/Silkscreen Bottom")
		(1 "F.Mask" user "Board Geometry/Soldermask Top")
		(3 "B.Mask" user "Board Geometry/Soldermask Bottom")
		(17 "Dwgs.User" user "User.Drawings")
		(19 "Cmts.User" user "User.Comments")
		(21 "Eco1.User" user "User.Eco1")
		(23 "Eco2.User" user "User.Eco2")
		(25 "Edge.Cuts" user "Board Geometry/Outline")
		(27 "Margin" user)
		(31 "F.CrtYd" user "Package Geometry/Place Bound Top")
		(29 "B.CrtYd" user "Package Geometry/Place Bound Bottom")
		(35 "F.Fab" user "Ref Des/Assembly Top")
		(33 "B.Fab" user "Ref Des/Assembly Bottom")
	)
	(footprint ""
		(layer "F.Cu")
		(at 31.75 -26.67 180)
		(property "Reference" "U34"
			(at -1.432052 -0.5842 90)
			(unlocked yes)
			(layer "F.SilkS")
			(effects
				(font
					(size 0.7874 0.5842)
					(thickness 0.1524)
				)
				(justify left)
			)
		)
		(property "Value" ""
			(at 0 0 180)
			(layer "F.Fab")
			(effects
				(font
					(size 1.27 1.27)
				)
			)
		)
		(duplicate_pad_numbers_are_jumpers no)
		(fp_line
			(start 0.791464 1.287526)
			(end 0.791464 -1.287526)
			(stroke
				(width 0.1524)
				(type default)
			)
			(layer "F.SilkS")
		)
		(fp_line
			(start 0.791464 -1.287526)
			(end -0.791464 -1.287526)
			(stroke
				(width 0.1524)
				(type default)
			)
			(layer "F.SilkS")
		)
		(fp_line
			(start -0.791464 1.287526)
			(end 0.791464 1.287526)
			(stroke
				(width 0.1524)
				(type default)
			)
			(layer "F.SilkS")
		)
		(fp_line
			(start -0.791464 -1.287526)
			(end -0.791464 1.287526)
			(stroke
				(width 0.1524)
				(type default)
			)
			(layer "F.SilkS")
		)
		(fp_poly
			(pts
				(xy -1.651 -1.253998) (xy -1.651 -0.745998) (xy -1.143 -0.999998)
			)
			(stroke
				(width 0)
				(type default)
			)
			(fill yes)
			(layer "F.SilkS")
		)
		(fp_line
			(start 0.537464 1.287526)
			(end 0.537464 -1.287526)
			(stroke
				(width 0.1)
				(type default)
			)
			(layer "F.Fab")
		)
		(fp_line
			(start 0.537464 -1.287526)
			(end -0.537464 -1.287526)
			(stroke
				(width 0.1)
				(type default)
			)
			(layer "F.Fab")
		)
		(fp_line
			(start -0.537464 1.287526)
			(end 0.537464 1.287526)
			(stroke
				(width 0.1)
				(type default)
			)
			(layer "F.Fab")
		)
		(fp_line
			(start -0.537464 -1.287526)
			(end -0.537464 1.287526)
			(stroke
				(width 0.1)
				(type default)
			)
			(layer "F.Fab")
		)
		(fp_poly
			(pts
				(xy -1.651 -1.253998) (xy -1.651 -0.745998) (xy -1.143 -0.999998)
			)
			(stroke
				(width 0)
				(type default)
			)
			(fill yes)
			(layer "F.Fab")
		)
		(pad "1" smd rect
			(at -0.387604 -0.999998 270)
			(size 0.254 0.635)
			(layers "F.Cu" "F.Mask" "F.Paste")
			(net "V_BMC_LS_DDC_SCL_R")
		)
		(pad "2" smd rect
			(at -0.387604 -0.499872 270)
			(size 0.254 0.635)
			(layers "F.Cu" "F.Mask" "F.Paste")
			(net "V_BMC_LS_DDC_SDA_R")
		)
		(pad "3" smd rect
			(at -0.350012 0 270)
			(size 0.4572 0.6858)
			(layers "F.Cu" "F.Mask" "F.Paste")
			(net "GND")
		)
		(pad "4" smd rect
			(at -0.387604 0.499872 270)
			(size 0.254 0.635)
			(layers "F.Cu" "F.Mask" "F.Paste")
			(net "V_VGAHS_BUF")
		)
		(pad "5" smd rect
			(at -0.387604 0.999998 270)
			(size 0.254 0.635)
			(layers "F.Cu" "F.Mask" "F.Paste")
			(net "V_VGAVS_BUF")
		)
		(pad "6" smd rect
			(at 0.387604 0.999998 270)
			(size 0.254 0.635)
			(layers "F.Cu" "F.Mask" "F.Paste")
			(net "V_VGAVS_BUF")
		)
		(pad "7" smd rect
			(at 0.387604 0.499872 270)
			(size 0.254 0.635)
			(layers "F.Cu" "F.Mask" "F.Paste")
			(net "V_VGAHS_BUF")
		)
		(pad "8" smd rect
			(at 0.412496 0 270)
			(size 0.4572 0.5842)
			(layers "F.Cu" "F.Mask" "F.Paste")
			(net "GND")
		)
		(pad "9" smd rect
			(at 0.387604 -0.499872 270)
			(size 0.254 0.635)
			(layers "F.Cu" "F.Mask" "F.Paste")
			(net "V_BMC_LS_DDC_SDA_R")
		)
		(pad "10" smd rect
			(at 0.387604 -0.999998 270)
			(size 0.254 0.635)
			(layers "F.Cu" "F.Mask" "F.Paste")
			(net "V_BMC_LS_DDC_SCL_R")
		)
	)
	(footprint ""
		(layer "F.Cu")
		(at 11.070844 -14.812518)
		(property "Reference" "C200"
			(at 0 0 0)
			(layer "F.SilkS")
			(hide yes)
			(effects
				(font
					(size 1.27 1.27)
				)
			)
		)
		(property "Value" ""
			(at 0 0 0)
			(layer "F.Fab")
			(effects
				(font
					(size 1.27 1.27)
				)
			)
		)
		(duplicate_pad_numbers_are_jumpers no)
		(fp_line
			(start -0.7874 -0.4064)
			(end 0.7874 -0.4064)
			(stroke
				(width 0.1524)
				(type default)
			)
			(layer "F.SilkS")
		)
		(fp_line
			(start -0.7874 0.4064)
			(end -0.7874 -0.4064)
			(stroke
				(width 0.1524)
				(type default)
			)
			(layer "F.SilkS")
		)
		(fp_line
			(start 0.7874 -0.4064)
			(end 0.7874 0.4064)
			(stroke
				(width 0.1524)
				(type default)
			)
			(layer "F.SilkS")
		)
		(fp_line
			(start 0.7874 0.4064)
			(end -0.7874 0.4064)
			(stroke
				(width 0.1524)
				(type default)
			)
			(layer "F.SilkS")
		)
		(fp_line
			(start -0.67945 -0.305054)
			(end -0.12065 -0.305054)
			(stroke
				(width 0.1)
				(type default)
			)
			(layer "F.Fab")
		)
		(fp_line
			(start -0.67945 0.3048)
			(end -0.67945 -0.305054)
			(stroke
				(width 0.1)
				(type default)
			)
			(layer "F.Fab")
		)
		(fp_line
			(start -0.12065 -0.305054)
			(end -0.12065 -0.2794)
			(stroke
				(width 0.1)
				(type default)
			)
			(layer "F.Fab")
		)
		(fp_line
			(start -0.12065 -0.2794)
			(end 0.12065 -0.2794)
			(stroke
				(width 0.1)
				(type default)
			)
			(layer "F.Fab")
		)
		(fp_line
			(start -0.12065 0.2794)
			(end -0.12065 0.3048)
			(stroke
				(width 0.1)
				(type default)
			)
			(layer "F.Fab")
		)
		(fp_line
			(start -0.12065 0.3048)
			(end -0.67945 0.3048)
			(stroke
				(width 0.1)
				(type default)
			)
			(layer "F.Fab")
		)
		(fp_line
			(start 0.120396 0.2794)
			(end -0.12065 0.2794)
			(stroke
				(width 0.1)
				(type default)
			)
			(layer "F.Fab")
		)
		(fp_line
			(start 0.120396 0.3048)
			(end 0.120396 0.2794)
			(stroke
				(width 0.1)
				(type default)
			)
			(layer "F.Fab")
		)
		(fp_line
			(start 0.12065 -0.3048)
			(end 0.67945 -0.3048)
			(stroke
				(width 0.1)
				(type default)
			)
			(layer "F.Fab")
		)
		(fp_line
			(start 0.12065 -0.2794)
			(end 0.12065 -0.3048)
			(stroke
				(width 0.1)
				(type default)
			)
			(layer "F.Fab")
		)
		(fp_line
			(start 0.67945 -0.3048)
			(end 0.67945 0.3048)
			(stroke
				(width 0.1)
				(type default)
			)
			(layer "F.Fab")
		)
		(fp_line
			(start 0.67945 0.3048)
			(end 0.120396 0.3048)
			(stroke
				(width 0.1)
				(type default)
			)
			(layer "F.Fab")
		)
		(pad "1" smd circle
			(at -0.40005 0)
			(size 0 0)
			(layers "F.Cu" "F.Mask" "F.Paste")
			(net "P3V3_AUX")
		)
		(pad "2" smd circle
			(at 0.40005 0)
			(size 0 0)
			(layers "F.Cu" "F.Mask" "F.Paste")
			(net "GND")
		)
	)
)
